# T6G (Grand Teton) — schematic netlist excerpt (pin names and nets, part order shuffled) for the footprints in the layout excerpt that follows; sources: Cadence DE-HDL packaged netlist, KiCad conversion of 04192023_DAF0TMB3IC0_F0TG_MB_C_brd_V02_OCP.brd

C335  Q_CAP  22UF 4V 20% X6S  pkg C0402  page 334 : A = P0V9_CPU1_RT1_2A ; B = GND
R491  Q_RES  4.7K 5% EMPTY  pkg 0402LF  page 55 : A = GND ; B = CPU1_PWRGD_OUT
R666  Q_RES  49.9 1% CHIP  pkg 0201LF  page 276 : A = SMB_RT_CPU0_P0_ROM_MUX_1D_SCL ; B = SMB_RT_CPU0_P0_ROM_MUX_1D_R_SCL

(kicad_pcb
	(version 20260206)
	(generator "pcbnew")
	(generator_version "10.0")
	(general
		(thickness 1.6)
		(legacy_teardrops no)
	)
	(paper "A4")
	(title_block
		(title "04192023_DAF0TMB3IC0_F0TG_MB_C_brd_V02_OCP.brd")
		(comment 1 "Grand Teton / footprints 8061-8063 of 8354")
	)
	(layers
		(0 "F.Cu" signal "TOP")
		(4 "In1.Cu" signal "GND")
		(6 "In2.Cu" signal "IN1")
		(8 "In3.Cu" signal "GND1")
		(10 "In4.Cu" signal "IN2")
		(12 "In5.Cu" signal "GND2")
		(14 "In6.Cu" signal "IN3")
		(16 "In7.Cu" signal "GND3")
		(18 "In8.Cu" signal "VCC")
		(20 "In9.Cu" signal "VCC1")
		(22 "In10.Cu" signal "GND4")
		(24 "In11.Cu" signal "IN4")
		(26 "In12.Cu" signal "GND5")
		(28 "In13.Cu" signal "IN5")
		(30 "In14.Cu" signal "GND6")
		(32 "In15.Cu" signal "IN6")
		(34 "In16.Cu" signal "GND7")
		(2 "B.Cu" signal "BOTTOM")
		(9 "F.Adhes" user "F.Adhesive")
		(11 "B.Adhes" user "B.Adhesive")
		(13 "F.Paste" user "Package Geometry/Pastemask Top")
		(15 "B.Paste" user "Package Geometry/Pastemask Bottom")
		(5 "F.SilkS" user "Ref Des/Silkscreen Top")
		(7 "B.SilkS" user "Ref Des/Silkscreen Bottom")
		(1 "F.Mask" user "Board Geometry/Soldermask Top")
		(3 "B.Mask" user "Board Geometry/Soldermask Bottom")
		(17 "Dwgs.User" user "User.Drawings")
		(19 "Cmts.User" user "User.Comments")
		(21 "Eco1.User" user "User.Eco1")
		(23 "Eco2.User" user "User.Eco2")
		(25 "Edge.Cuts" user "Board Geometry/Outline")
		(27 "Margin" user)
		(31 "F.CrtYd" user "Package Geometry/Place Bound Top")
		(29 "B.CrtYd" user "Package Geometry/Place Bound Bottom")
		(35 "F.Fab" user "Ref Des/Assembly Top")
		(33 "B.Fab" user "Ref Des/Assembly Bottom")
	)
	(footprint ""
		(layer "B.Cu")
		(at 95.518986 -390.560052 90)
		(property "Reference" "C335"
			(at 0 0 90)
			(layer "B.SilkS")
			(hide yes)
			(effects
				(font
					(size 1.27 1.27)
				)
				(justify mirror)
			)
		)
		(property "Value" ""
			(at 0 0 90)
			(layer "B.Fab")
			(effects
				(font
					(size 1.27 1.27)
				)
				(justify mirror)
			)
		)
		(duplicate_pad_numbers_are_jumpers no)
		(fp_line
			(start 0.7874 -0.4064)
			(end -0.7874 -0.4064)
			(stroke
				(width 0.1524)
				(type default)
			)
			(layer "B.SilkS")
		)
		(fp_line
			(start -0.7874 -0.4064)
			(end -0.7874 0.4064)
			(stroke
				(width 0.1524)
				(type default)
			)
			(layer "B.SilkS")
		)
		(fp_line
			(start 0.7874 0.4064)
			(end 0.7874 -0.4064)
			(stroke
				(width 0.1524)
				(type default)
			)
			(layer "B.SilkS")
		)
		(fp_line
			(start -0.7874 0.4064)
			(end 0.7874 0.4064)
			(stroke
				(width 0.1524)
				(type default)
			)
			(layer "B.SilkS")
		)
		(fp_line
			(start 0.67945 -0.305054)
			(end 0.12065 -0.305054)
			(stroke
				(width 0.1)
				(type default)
			)
			(layer "B.Fab")
		)
		(fp_line
			(start 0.12065 -0.305054)
			(end 0.12065 -0.2794)
			(stroke
				(width 0.1)
				(type default)
			)
			(layer "B.Fab")
		)
		(fp_line
			(start -0.12065 -0.3048)
			(end -0.67945 -0.3048)
			(stroke
				(width 0.1)
				(type default)
			)
			(layer "B.Fab")
		)
		(fp_line
			(start -0.67945 -0.3048)
			(end -0.67945 0.3048)
			(stroke
				(width 0.1)
				(type default)
			)
			(layer "B.Fab")
		)
		(fp_line
			(start 0.12065 -0.2794)
			(end -0.12065 -0.2794)
			(stroke
				(width 0.1)
				(type default)
			)
			(layer "B.Fab")
		)
		(fp_line
			(start -0.12065 -0.2794)
			(end -0.12065 -0.3048)
			(stroke
				(width 0.1)
				(type default)
			)
			(layer "B.Fab")
		)
		(fp_line
			(start 0.12065 0.2794)
			(end 0.12065 0.3048)
			(stroke
				(width 0.1)
				(type default)
			)
			(layer "B.Fab")
		)
		(fp_line
			(start -0.120396 0.2794)
			(end 0.12065 0.2794)
			(stroke
				(width 0.1)
				(type default)
			)
			(layer "B.Fab")
		)
		(fp_line
			(start 0.67945 0.3048)
			(end 0.67945 -0.305054)
			(stroke
				(width 0.1)
				(type default)
			)
			(layer "B.Fab")
		)
		(fp_line
			(start 0.12065 0.3048)
			(end 0.67945 0.3048)
			(stroke
				(width 0.1)
				(type default)
			)
			(layer "B.Fab")
		)
		(fp_line
			(start -0.120396 0.3048)
			(end -0.120396 0.2794)
			(stroke
				(width 0.1)
				(type default)
			)
			(layer "B.Fab")
		)
		(fp_line
			(start -0.67945 0.3048)
			(end -0.120396 0.3048)
			(stroke
				(width 0.1)
				(type default)
			)
			(layer "B.Fab")
		)
		(pad "1" smd circle
			(at 0.40005 0 270)
			(size 0 0)
			(layers "B.Cu" "B.Mask" "B.Paste")
			(net "P0V9_CPU1_RT1_2A")
		)
		(pad "2" smd circle
			(at -0.40005 0 270)
			(size 0 0)
			(layers "B.Cu" "B.Mask" "B.Paste")
			(net "GND")
		)
	)
	(footprint ""
		(layer "B.Cu")
		(at 301.377604 -426.498512 180)
		(property "Reference" "R666"
			(at 0 0 0)
			(layer "B.SilkS")
			(hide yes)
			(effects
				(font
					(size 1.27 1.27)
				)
				(justify mirror)
			)
		)
		(property "Value" ""
			(at 0 0 0)
			(layer "B.Fab")
			(effects
				(font
					(size 1.27 1.27)
				)
				(justify mirror)
			)
		)
		(duplicate_pad_numbers_are_jumpers no)
		(fp_line
			(start 0.32512 0.175006)
			(end 0.32512 -0.175006)
			(stroke
				(width 0.1)
				(type default)
			)
			(layer "B.Fab")
		)
		(fp_line
			(start 0.32512 -0.175006)
			(end -0.32512 -0.175006)
			(stroke
				(width 0.1)
				(type default)
			)
			(layer "B.Fab")
		)
		(fp_line
			(start -0.32512 0.175006)
			(end 0.32512 0.175006)
			(stroke
				(width 0.1)
				(type default)
			)
			(layer "B.Fab")
		)
		(fp_line
			(start -0.32512 -0.175006)
			(end -0.32512 0.175006)
			(stroke
				(width 0.1)
				(type default)
			)
			(layer "B.Fab")
		)
		(pad "1" smd rect
			(at 0.2667 0)
			(size 0.3048 0.381)
			(layers "B.Cu" "B.Mask" "B.Paste")
			(net "SMB_RT_CPU0_P0_ROM_MUX_1D_SCL")
		)
		(pad "2" smd rect
			(at -0.2667 0 180)
			(size 0.3048 0.381)
			(layers "B.Cu" "B.Mask" "B.Paste")
			(net "SMB_RT_CPU0_P0_ROM_MUX_1D_R_SCL")
		)
	)
	(footprint ""
		(layer "B.Cu")
		(at 94.460314 -307.730652 180)
		(property "Reference" "R491"
			(at 0 0 0)
			(layer "B.SilkS")
			(hide yes)
			(effects
				(font
					(size 1.27 1.27)
				)
				(justify mirror)
			)
		)
		(property "Value" ""
			(at 0 0 0)
			(layer "B.Fab")
			(effects
				(font
					(size 1.27 1.27)
				)
				(justify mirror)
			)
		)
		(duplicate_pad_numbers_are_jumpers no)
		(fp_line
			(start 0.7874 0.4064)
			(end 0.7874 -0.4064)
			(stroke
				(width 0.1524)
				(type default)
			)
			(layer "B.SilkS")
		)
		(fp_line
			(start 0.7874 -0.4064)
			(end -0.7874 -0.4064)
			(stroke
				(width 0.1524)
				(type default)
			)
			(layer "B.SilkS")
		)
		(fp_line
			(start -0.7874 0.4064)
			(end 0.7874 0.4064)
			(stroke
				(width 0.1524)
				(type default)
			)
			(layer "B.SilkS")
		)
		(fp_line
			(start -0.7874 -0.4064)
			(end -0.7874 0.4064)
			(stroke
				(width 0.1524)
				(type default)
			)
			(layer "B.SilkS")
		)
		(fp_line
			(start 0.67945 0.3048)
			(end 0.67945 -0.305054)
			(stroke
				(width 0.1)
				(type default)
			)
			(layer "B.Fab")
		)
		(fp_line
			(start 0.67945 -0.305054)
			(end 0.12065 -0.305054)
			(stroke
				(width 0.1)
				(type default)
			)
			(layer "B.Fab")
		)
		(fp_line
			(start 0.12065 0.3048)
			(end 0.67945 0.3048)
			(stroke
				(width 0.1)
				(type default)
			)
			(layer "B.Fab")
		)
		(fp_line
			(start 0.12065 0.2794)
			(end 0.12065 0.3048)
			(stroke
				(width 0.1)
				(type default)
			)
			(layer "B.Fab")
		)
		(fp_line
			(start 0.12065 -0.2794)
			(end -0.12065 -0.2794)
			(stroke
				(width 0.1)
				(type default)
			)
			(layer "B.Fab")
		)
		(fp_line
			(start 0.12065 -0.305054)
			(end 0.12065 -0.2794)
			(stroke
				(width 0.1)
				(type default)
			)
			(layer "B.Fab")
		)
		(fp_line
			(start -0.120396 0.3048)
			(end -0.120396 0.2794)
			(stroke
				(width 0.1)
				(type default)
			)
			(layer "B.Fab")
		)
		(fp_line
			(start -0.120396 0.2794)
			(end 0.12065 0.2794)
			(stroke
				(width 0.1)
				(type default)
			)
			(layer "B.Fab")
		)
		(fp_line
			(start -0.12065 -0.2794)
			(end -0.12065 -0.3048)
			(stroke
				(width 0.1)
				(type default)
			)
			(layer "B.Fab")
		)
		(fp_line
			(start -0.12065 -0.3048)
			(end -0.67945 -0.3048)
			(stroke
				(width 0.1)
				(type default)
			)
			(layer "B.Fab")
		)
		(fp_line
			(start -0.67945 0.3048)
			(end -0.120396 0.3048)
			(stroke
				(width 0.1)
				(type default)
			)
			(layer "B.Fab")
		)
		(fp_line
			(start -0.67945 -0.3048)
			(end -0.67945 0.3048)
			(stroke
				(width 0.1)
				(type default)
			)
			(layer "B.Fab")
		)
		(pad "1" smd circle
			(at 0.40005 0)
			(size 0 0)
			(layers "B.Cu" "B.Mask" "B.Paste")
			(net "GND")
		)
		(pad "2" smd circle
			(at -0.40005 0)
			(size 0 0)
			(layers "B.Cu" "B.Mask" "B.Paste")
			(net "CPU1_PWRGD_OUT")
		)
	)
)
